(kicad_pcb
	(version 20260206)
	(generator "pcbnew")
	(generator_version "10.0")
	(general
		(thickness 1.6)
		(legacy_teardrops no)
	)
	(paper "A4")
	(title_block
		(title "03242023_DA0F0TMBIJ0_F0T_Motherboard_J_brd_V01_OCP.brd")
		(comment 1 "Grand Teton / footprints 1573-1579 of 6105")
	)
	(layers
		(0 "F.Cu" signal "TOP")
		(4 "In1.Cu" signal "GND")
		(6 "In2.Cu" signal "IN1")
		(8 "In3.Cu" signal "GND1")
		(10 "In4.Cu" signal "IN2")
		(12 "In5.Cu" signal "GND2")
		(14 "In6.Cu" signal "IN3")
		(16 "In7.Cu" signal "GND3")
		(18 "In8.Cu" signal "VCC")
		(20 "In9.Cu" signal "VCC1")
		(22 "In10.Cu" signal "GND4")
		(24 "In11.Cu" signal "IN4")
		(26 "In12.Cu" signal "GND5")
		(28 "In13.Cu" signal "IN5")
		(30 "In14.Cu" signal "GND6")
		(32 "In15.Cu" signal "IN6")
		(34 "In16.Cu" signal "GND7")
		(2 "B.Cu" signal "BOTTOM")
		(9 "F.Adhes" user "F.Adhesive")
		(11 "B.Adhes" user "B.Adhesive")
		(13 "F.Paste" user "Package Geometry/Pastemask Top")
		(15 "B.Paste" user "Package Geometry/Pastemask Bottom")
		(5 "F.SilkS" user "Ref Des/Silkscreen Top")
		(7 "B.SilkS" user "Ref Des/Silkscreen Bottom")
		(1 "F.Mask" user "Board Geometry/Soldermask Top")
		(3 "B.Mask" user "Board Geometry/Soldermask Bottom")
		(17 "Dwgs.User" user "User.Drawings")
		(19 "Cmts.User" user "User.Comments")
		(21 "Eco1.User" user "User.Eco1")
		(23 "Eco2.User" user "User.Eco2")
		(25 "Edge.Cuts" user "Board Geometry/Outline")
		(27 "Margin" user)
		(31 "F.CrtYd" user "Package Geometry/Place Bound Top")
		(29 "B.CrtYd" user "Package Geometry/Place Bound Bottom")
		(35 "F.Fab" user "Ref Des/Assembly Top")
		(33 "B.Fab" user "Ref Des/Assembly Bottom")
	)
	(footprint ""
		(layer "F.Cu")
		(at 144.294606 -78.955138 180)
		(property "Reference" "R2355"
			(at 0 0 180)
			(layer "F.SilkS")
			(hide yes)
			(effects
				(font
					(size 1.27 1.27)
				)
			)
		)
		(property "Value" ""
			(at 0 0 180)
			(layer "F.Fab")
			(effects
				(font
					(size 1.27 1.27)
				)
			)
		)
		(duplicate_pad_numbers_are_jumpers no)
		(fp_line
			(start 0.7874 0.4064)
			(end -0.7874 0.4064)
			(stroke
				(width 0.1524)
				(type default)
			)
			(layer "F.SilkS")
		)
		(fp_line
			(start 0.7874 -0.4064)
			(end 0.7874 0.4064)
			(stroke
				(width 0.1524)
				(type default)
			)
			(layer "F.SilkS")
		)
		(fp_line
			(start -0.7874 0.4064)
			(end -0.7874 -0.4064)
			(stroke
				(width 0.1524)
				(type default)
			)
			(layer "F.SilkS")
		)
		(fp_line
			(start -0.7874 -0.4064)
			(end 0.7874 -0.4064)
			(stroke
				(width 0.1524)
				(type default)
			)
			(layer "F.SilkS")
		)
		(fp_line
			(start 0.67945 0.3048)
			(end 0.120396 0.3048)
			(stroke
				(width 0.1)
				(type default)
			)
			(layer "F.Fab")
		)
		(fp_line
			(start 0.67945 -0.3048)
			(end 0.67945 0.3048)
			(stroke
				(width 0.1)
				(type default)
			)
			(layer "F.Fab")
		)
		(fp_line
			(start 0.12065 -0.2794)
			(end 0.12065 -0.3048)
			(stroke
				(width 0.1)
				(type default)
			)
			(layer "F.Fab")
		)
		(fp_line
			(start 0.12065 -0.3048)
			(end 0.67945 -0.3048)
			(stroke
				(width 0.1)
				(type default)
			)
			(layer "F.Fab")
		)
		(fp_line
			(start 0.120396 0.3048)
			(end 0.120396 0.2794)
			(stroke
				(width 0.1)
				(type default)
			)
			(layer "F.Fab")
		)
		(fp_line
			(start 0.120396 0.2794)
			(end -0.12065 0.2794)
			(stroke
				(width 0.1)
				(type default)
			)
			(layer "F.Fab")
		)
		(fp_line
			(start -0.12065 0.3048)
			(end -0.67945 0.3048)
			(stroke
				(width 0.1)
				(type default)
			)
			(layer "F.Fab")
		)
		(fp_line
			(start -0.12065 0.2794)
			(end -0.12065 0.3048)
			(stroke
				(width 0.1)
				(type default)
			)
			(layer "F.Fab")
		)
		(fp_line
			(start -0.12065 -0.2794)
			(end 0.12065 -0.2794)
			(stroke
				(width 0.1)
				(type default)
			)
			(layer "F.Fab")
		)
		(fp_line
			(start -0.12065 -0.305054)
			(end -0.12065 -0.2794)
			(stroke
				(width 0.1)
				(type default)
			)
			(layer "F.Fab")
		)
		(fp_line
			(start -0.67945 0.3048)
			(end -0.67945 -0.305054)
			(stroke
				(width 0.1)
				(type default)
			)
			(layer "F.Fab")
		)
		(fp_line
			(start -0.67945 -0.305054)
			(end -0.12065 -0.305054)
			(stroke
				(width 0.1)
				(type default)
			)
			(layer "F.Fab")
		)
		(pad "1" smd circle
			(at -0.40005 0 180)
			(size 0 0)
			(layers "F.Cu" "F.Mask" "F.Paste")
			(net "P3V3_AUX")
		)
		(pad "2" smd circle
			(at 0.40005 0 180)
			(size 0 0)
			(layers "F.Cu" "F.Mask" "F.Paste")
			(net "FM_PS_EN_PLD_BUF1")
		)
	)
	(footprint ""
		(layer "F.Cu")
		(at 104.3432 -249.320558 -90)
		(property "Reference" "C232"
			(at 0 0 270)
			(layer "F.SilkS")
			(hide yes)
			(effects
				(font
					(size 1.27 1.27)
				)
			)
		)
		(property "Value" ""
			(at 0 0 270)
			(layer "F.Fab")
			(effects
				(font
					(size 1.27 1.27)
				)
			)
		)
		(duplicate_pad_numbers_are_jumpers no)
		(fp_line
			(start -0.7874 0.4064)
			(end -0.7874 -0.4064)
			(stroke
				(width 0.1524)
				(type default)
			)
			(layer "F.SilkS")
		)
		(fp_line
			(start 0.7874 0.4064)
			(end -0.7874 0.4064)
			(stroke
				(width 0.1524)
				(type default)
			)
			(layer "F.SilkS")
		)
		(fp_line
			(start -0.7874 -0.4064)
			(end 0.7874 -0.4064)
			(stroke
				(width 0.1524)
				(type default)
			)
			(layer "F.SilkS")
		)
		(fp_line
			(start 0.7874 -0.4064)
			(end 0.7874 0.4064)
			(stroke
				(width 0.1524)
				(type default)
			)
			(layer "F.SilkS")
		)
		(fp_line
			(start -0.67945 0.3048)
			(end -0.67945 -0.305054)
			(stroke
				(width 0.1)
				(type default)
			)
			(layer "F.Fab")
		)
		(fp_line
			(start -0.12065 0.3048)
			(end -0.67945 0.3048)
			(stroke
				(width 0.1)
				(type default)
			)
			(layer "F.Fab")
		)
		(fp_line
			(start 0.120396 0.3048)
			(end 0.120396 0.2794)
			(stroke
				(width 0.1)
				(type default)
			)
			(layer "F.Fab")
		)
		(fp_line
			(start 0.67945 0.3048)
			(end 0.120396 0.3048)
			(stroke
				(width 0.1)
				(type default)
			)
			(layer "F.Fab")
		)
		(fp_line
			(start -0.12065 0.2794)
			(end -0.12065 0.3048)
			(stroke
				(width 0.1)
				(type default)
			)
			(layer "F.Fab")
		)
		(fp_line
			(start 0.120396 0.2794)
			(end -0.12065 0.2794)
			(stroke
				(width 0.1)
				(type default)
			)
			(layer "F.Fab")
		)
		(fp_line
			(start -0.12065 -0.2794)
			(end 0.12065 -0.2794)
			(stroke
				(width 0.1)
				(type default)
			)
			(layer "F.Fab")
		)
		(fp_line
			(start 0.12065 -0.2794)
			(end 0.12065 -0.3048)
			(stroke
				(width 0.1)
				(type default)
			)
			(layer "F.Fab")
		)
		(fp_line
			(start 0.12065 -0.3048)
			(end 0.67945 -0.3048)
			(stroke
				(width 0.1)
				(type default)
			)
			(layer "F.Fab")
		)
		(fp_line
			(start 0.67945 -0.3048)
			(end 0.67945 0.3048)
			(stroke
				(width 0.1)
				(type default)
			)
			(layer "F.Fab")
		)
		(fp_line
			(start -0.67945 -0.305054)
			(end -0.12065 -0.305054)
			(stroke
				(width 0.1)
				(type default)
			)
			(layer "F.Fab")
		)
		(fp_line
			(start -0.12065 -0.305054)
			(end -0.12065 -0.2794)
			(stroke
				(width 0.1)
				(type default)
			)
			(layer "F.Fab")
		)
		(pad "1" smd circle
			(at -0.40005 0 270)
			(size 0 0)
			(layers "F.Cu" "F.Mask" "F.Paste")
			(net "PVCCIN_CPU1")
		)
		(pad "2" smd circle
			(at 0.40005 0 270)
			(size 0 0)
			(layers "F.Cu" "F.Mask" "F.Paste")
			(net "GND")
		)
	)
	(footprint ""
		(layer "F.Cu")
		(at 307.017928 -402.371052 -90)
		(property "Reference" "C1577"
			(at 0 0 270)
			(layer "F.SilkS")
			(hide yes)
			(effects
				(font
					(size 1.27 1.27)
				)
			)
		)
		(property "Value" ""
			(at 0 0 270)
			(layer "F.Fab")
			(effects
				(font
					(size 1.27 1.27)
				)
			)
		)
		(duplicate_pad_numbers_are_jumpers no)
		(fp_line
			(start -0.299974 0.150114)
			(end -0.299974 -0.150114)
			(stroke
				(width 0.1)
				(type default)
			)
			(layer "F.Fab")
		)
		(fp_line
			(start 0.299974 0.150114)
			(end -0.299974 0.150114)
			(stroke
				(width 0.1)
				(type default)
			)
			(layer "F.Fab")
		)
		(fp_line
			(start -0.299974 -0.150114)
			(end 0.299974 -0.150114)
			(stroke
				(width 0.1)
				(type default)
			)
			(layer "F.Fab")
		)
		(fp_line
			(start 0.299974 -0.150114)
			(end 0.299974 0.150114)
			(stroke
				(width 0.1)
				(type default)
			)
			(layer "F.Fab")
		)
		(pad "1" smd rect
			(at -0.2667 0 270)
			(size 0.3048 0.381)
			(layers "F.Cu" "F.Mask" "F.Paste")
			(net "P5E_CPU0_PE4_TX_C_DP<1>")
		)
		(pad "2" smd rect
			(at 0.2667 0 270)
			(size 0.3048 0.381)
			(layers "F.Cu" "F.Mask" "F.Paste")
			(net "P5E_CPU0_PE4_TX_DP<1>")
		)
	)
	(footprint ""
		(layer "F.Cu")
		(at 449.973954 -117.193822 180)
		(property "Reference" "R1124"
			(at 0 0 180)
			(layer "F.SilkS")
			(hide yes)
			(effects
				(font
					(size 1.27 1.27)
				)
			)
		)
		(property "Value" ""
			(at 0 0 180)
			(layer "F.Fab")
			(effects
				(font
					(size 1.27 1.27)
				)
			)
		)
		(duplicate_pad_numbers_are_jumpers no)
		(fp_line
			(start 0.7874 0.4064)
			(end -0.7874 0.4064)
			(stroke
				(width 0.1524)
				(type default)
			)
			(layer "F.SilkS")
		)
		(fp_line
			(start 0.7874 -0.4064)
			(end 0.7874 0.4064)
			(stroke
				(width 0.1524)
				(type default)
			)
			(layer "F.SilkS")
		)
		(fp_line
			(start -0.7874 0.4064)
			(end -0.7874 -0.4064)
			(stroke
				(width 0.1524)
				(type default)
			)
			(layer "F.SilkS")
		)
		(fp_line
			(start -0.7874 -0.4064)
			(end 0.7874 -0.4064)
			(stroke
				(width 0.1524)
				(type default)
			)
			(layer "F.SilkS")
		)
		(fp_line
			(start 0.67945 0.3048)
			(end 0.120396 0.3048)
			(stroke
				(width 0.1)
				(type default)
			)
			(layer "F.Fab")
		)
		(fp_line
			(start 0.67945 -0.3048)
			(end 0.67945 0.3048)
			(stroke
				(width 0.1)
				(type default)
			)
			(layer "F.Fab")
		)
		(fp_line
			(start 0.12065 -0.2794)
			(end 0.12065 -0.3048)
			(stroke
				(width 0.1)
				(type default)
			)
			(layer "F.Fab")
		)
		(fp_line
			(start 0.12065 -0.3048)
			(end 0.67945 -0.3048)
			(stroke
				(width 0.1)
				(type default)
			)
			(layer "F.Fab")
		)
		(fp_line
			(start 0.120396 0.3048)
			(end 0.120396 0.2794)
			(stroke
				(width 0.1)
				(type default)
			)
			(layer "F.Fab")
		)
		(fp_line
			(start 0.120396 0.2794)
			(end -0.12065 0.2794)
			(stroke
				(width 0.1)
				(type default)
			)
			(layer "F.Fab")
		)
		(fp_line
			(start -0.12065 0.3048)
			(end -0.67945 0.3048)
			(stroke
				(width 0.1)
				(type default)
			)
			(layer "F.Fab")
		)
		(fp_line
			(start -0.12065 0.2794)
			(end -0.12065 0.3048)
			(stroke
				(width 0.1)
				(type default)
			)
			(layer "F.Fab")
		)
		(fp_line
			(start -0.12065 -0.2794)
			(end 0.12065 -0.2794)
			(stroke
				(width 0.1)
				(type default)
			)
			(layer "F.Fab")
		)
		(fp_line
			(start -0.12065 -0.305054)
			(end -0.12065 -0.2794)
			(stroke
				(width 0.1)
				(type default)
			)
			(layer "F.Fab")
		)
		(fp_line
			(start -0.67945 0.3048)
			(end -0.67945 -0.305054)
			(stroke
				(width 0.1)
				(type default)
			)
			(layer "F.Fab")
		)
		(fp_line
			(start -0.67945 -0.305054)
			(end -0.12065 -0.305054)
			(stroke
				(width 0.1)
				(type default)
			)
			(layer "F.Fab")
		)
		(pad "1" smd circle
			(at -0.40005 0 180)
			(size 0 0)
			(layers "F.Cu" "F.Mask" "F.Paste")
			(net "PD_SMB_OCP1_HP_ADD2")
		)
		(pad "2" smd circle
			(at 0.40005 0 180)
			(size 0 0)
			(layers "F.Cu" "F.Mask" "F.Paste")
			(net "GND")
		)
	)
	(footprint ""
		(layer "F.Cu")
		(at 458.41666 -39.765478)
		(property "Reference" "C1173"
			(at 0 0 0)
			(layer "F.SilkS")
			(hide yes)
			(effects
				(font
					(size 1.27 1.27)
				)
			)
		)
		(property "Value" ""
			(at 0 0 0)
			(layer "F.Fab")
			(effects
				(font
					(size 1.27 1.27)
				)
			)
		)
		(duplicate_pad_numbers_are_jumpers no)
		(fp_line
			(start -0.7874 -0.4064)
			(end 0.7874 -0.4064)
			(stroke
				(width 0.1524)
				(type default)
			)
			(layer "F.SilkS")
		)
		(fp_line
			(start -0.7874 0.4064)
			(end -0.7874 -0.4064)
			(stroke
				(width 0.1524)
				(type default)
			)
			(layer "F.SilkS")
		)
		(fp_line
			(start 0.7874 -0.4064)
			(end 0.7874 0.4064)
			(stroke
				(width 0.1524)
				(type default)
			)
			(layer "F.SilkS")
		)
		(fp_line
			(start 0.7874 0.4064)
			(end -0.7874 0.4064)
			(stroke
				(width 0.1524)
				(type default)
			)
			(layer "F.SilkS")
		)
		(fp_line
			(start -0.67945 -0.305054)
			(end -0.12065 -0.305054)
			(stroke
				(width 0.1)
				(type default)
			)
			(layer "F.Fab")
		)
		(fp_line
			(start -0.67945 0.3048)
			(end -0.67945 -0.305054)
			(stroke
				(width 0.1)
				(type default)
			)
			(layer "F.Fab")
		)
		(fp_line
			(start -0.12065 -0.305054)
			(end -0.12065 -0.2794)
			(stroke
				(width 0.1)
				(type default)
			)
			(layer "F.Fab")
		)
		(fp_line
			(start -0.12065 -0.2794)
			(end 0.12065 -0.2794)
			(stroke
				(width 0.1)
				(type default)
			)
			(layer "F.Fab")
		)
		(fp_line
			(start -0.12065 0.2794)
			(end -0.12065 0.3048)
			(stroke
				(width 0.1)
				(type default)
			)
			(layer "F.Fab")
		)
		(fp_line
			(start -0.12065 0.3048)
			(end -0.67945 0.3048)
			(stroke
				(width 0.1)
				(type default)
			)
			(layer "F.Fab")
		)
		(fp_line
			(start 0.120396 0.2794)
			(end -0.12065 0.2794)
			(stroke
				(width 0.1)
				(type default)
			)
			(layer "F.Fab")
		)
		(fp_line
			(start 0.120396 0.3048)
			(end 0.120396 0.2794)
			(stroke
				(width 0.1)
				(type default)
			)
			(layer "F.Fab")
		)
		(fp_line
			(start 0.12065 -0.3048)
			(end 0.67945 -0.3048)
			(stroke
				(width 0.1)
				(type default)
			)
			(layer "F.Fab")
		)
		(fp_line
			(start 0.12065 -0.2794)
			(end 0.12065 -0.3048)
			(stroke
				(width 0.1)
				(type default)
			)
			(layer "F.Fab")
		)
		(fp_line
			(start 0.67945 -0.3048)
			(end 0.67945 0.3048)
			(stroke
				(width 0.1)
				(type default)
			)
			(layer "F.Fab")
		)
		(fp_line
			(start 0.67945 0.3048)
			(end 0.120396 0.3048)
			(stroke
				(width 0.1)
				(type default)
			)
			(layer "F.Fab")
		)
		(pad "1" smd circle
			(at -0.40005 0)
			(size 0 0)
			(layers "F.Cu" "F.Mask" "F.Paste")
			(net "P3V3_AUX")
		)
		(pad "2" smd circle
			(at 0.40005 0)
			(size 0 0)
			(layers "F.Cu" "F.Mask" "F.Paste")
			(net "GND")
		)
	)
	(footprint ""
		(layer "F.Cu")
		(at 17.36471 -180.522626 90)
		(property "Reference" "PC1280"
			(at 0 0 90)
			(layer "F.SilkS")
			(hide yes)
			(effects
				(font
					(size 1.27 1.27)
				)
			)
		)
		(property "Value" ""
			(at 0 0 90)
			(layer "F.Fab")
			(effects
				(font
					(size 1.27 1.27)
				)
			)
		)
		(duplicate_pad_numbers_are_jumpers no)
		(fp_line
			(start 1.524 -0.762)
			(end 1.524 0.762)
			(stroke
				(width 0.1524)
				(type default)
			)
			(layer "F.SilkS")
		)
		(fp_line
			(start -1.524 -0.762)
			(end 1.524 -0.762)
			(stroke
				(width 0.1524)
				(type default)
			)
			(layer "F.SilkS")
		)
		(fp_line
			(start 1.524 0.762)
			(end -1.524 0.762)
			(stroke
				(width 0.1524)
				(type default)
			)
			(layer "F.SilkS")
		)
		(fp_line
			(start -1.524 0.762)
			(end -1.524 -0.762)
			(stroke
				(width 0.1524)
				(type default)
			)
			(layer "F.SilkS")
		)
		(fp_line
			(start 1.1049 -0.724916)
			(end -1.1049 -0.724916)
			(stroke
				(width 0.1)
				(type default)
			)
			(layer "F.Fab")
		)
		(fp_line
			(start -1.1049 -0.724916)
			(end -1.1049 0.724916)
			(stroke
				(width 0.1)
				(type default)
			)
			(layer "F.Fab")
		)
		(fp_line
			(start 1.1049 0.724916)
			(end 1.1049 -0.724916)
			(stroke
				(width 0.1)
				(type default)
			)
			(layer "F.Fab")
		)
		(fp_line
			(start -1.1049 0.724916)
			(end 1.1049 0.724916)
			(stroke
				(width 0.1)
				(type default)
			)
			(layer "F.Fab")
		)
		(pad "1" smd rect
			(at -0.889 0 270)
			(size 1.016 1.27)
			(layers "F.Cu" "F.Mask" "F.Paste")
			(net "SW_P12V_PVCCINFAON_CPU1_FLT")
		)
		(pad "2" smd rect
			(at 0.889 0 270)
			(size 1.016 1.27)
			(layers "F.Cu" "F.Mask" "F.Paste")
			(net "GND")
		)
	)
	(footprint ""
		(layer "F.Cu")
		(at 453.719946 -104.249728)
		(property "Reference" "R1906"
			(at 0 0 0)
			(layer "F.SilkS")
			(hide yes)
			(effects
				(font
					(size 1.27 1.27)
				)
			)
		)
		(property "Value" ""
			(at 0 0 0)
			(layer "F.Fab")
			(effects
				(font
					(size 1.27 1.27)
				)
			)
		)
		(duplicate_pad_numbers_are_jumpers no)
		(fp_line
			(start -0.7874 -0.4064)
			(end 0.7874 -0.4064)
			(stroke
				(width 0.1524)
				(type default)
			)
			(layer "F.SilkS")
		)
		(fp_line
			(start -0.7874 0.4064)
			(end -0.7874 -0.4064)
			(stroke
				(width 0.1524)
				(type default)
			)
			(layer "F.SilkS")
		)
		(fp_line
			(start 0.7874 -0.4064)
			(end 0.7874 0.4064)
			(stroke
				(width 0.1524)
				(type default)
			)
			(layer "F.SilkS")
		)
		(fp_line
			(start 0.7874 0.4064)
			(end -0.7874 0.4064)
			(stroke
				(width 0.1524)
				(type default)
			)
			(layer "F.SilkS")
		)
		(fp_line
			(start -0.67945 -0.305054)
			(end -0.12065 -0.305054)
			(stroke
				(width 0.1)
				(type default)
			)
			(layer "F.Fab")
		)
		(fp_line
			(start -0.67945 0.3048)
			(end -0.67945 -0.305054)
			(stroke
				(width 0.1)
				(type default)
			)
			(layer "F.Fab")
		)
		(fp_line
			(start -0.12065 -0.305054)
			(end -0.12065 -0.2794)
			(stroke
				(width 0.1)
				(type default)
			)
			(layer "F.Fab")
		)
		(fp_line
			(start -0.12065 -0.2794)
			(end 0.12065 -0.2794)
			(stroke
				(width 0.1)
				(type default)
			)
			(layer "F.Fab")
		)
		(fp_line
			(start -0.12065 0.2794)
			(end -0.12065 0.3048)
			(stroke
				(width 0.1)
				(type default)
			)
			(layer "F.Fab")
		)
		(fp_line
			(start -0.12065 0.3048)
			(end -0.67945 0.3048)
			(stroke
				(width 0.1)
				(type default)
			)
			(layer "F.Fab")
		)
		(fp_line
			(start 0.120396 0.2794)
			(end -0.12065 0.2794)
			(stroke
				(width 0.1)
				(type default)
			)
			(layer "F.Fab")
		)
		(fp_line
			(start 0.120396 0.3048)
			(end 0.120396 0.2794)
			(stroke
				(width 0.1)
				(type default)
			)
			(layer "F.Fab")
		)
		(fp_line
			(start 0.12065 -0.3048)
			(end 0.67945 -0.3048)
			(stroke
				(width 0.1)
				(type default)
			)
			(layer "F.Fab")
		)
		(fp_line
			(start 0.12065 -0.2794)
			(end 0.12065 -0.3048)
			(stroke
				(width 0.1)
				(type default)
			)
			(layer "F.Fab")
		)
		(fp_line
			(start 0.67945 -0.3048)
			(end 0.67945 0.3048)
			(stroke
				(width 0.1)
				(type default)
			)
			(layer "F.Fab")
		)
		(fp_line
			(start 0.67945 0.3048)
			(end 0.120396 0.3048)
			(stroke
				(width 0.1)
				(type default)
			)
			(layer "F.Fab")
		)
		(pad "1" smd circle
			(at -0.40005 0)
			(size 0 0)
			(layers "F.Cu" "F.Mask" "F.Paste")
			(net "P3V3_AUX")
		)
		(pad "2" smd circle
			(at 0.40005 0)
			(size 0 0)
			(layers "F.Cu" "F.Mask" "F.Paste")
			(net "OCP_SFF_PRSNT2_R_N")
		)
	)
)
